# S9S_MB_2U (Grand Teton) — schematic netlist excerpt (pin names and nets, part order shuffled) for the footprints in the layout excerpt that follows; sources: Cadence DE-HDL packaged netlist, KiCad conversion of 03242023_DA0F0TMBIJ0_F0T_Motherboard_J_brd_V01_OCP.brd

PC600  Q_CAP  2.2UF 10V 10% X6S  pkg C0402  page 271 : A = PVCCFA_EHV_FIVRA_CPU0_VDD1 ; B = GND
R1793  Q_RES  0 5% EMPTY  pkg 0402LF  page 250 : A = SMB_VR_3V3AUX_SCL_R1 ; B = SMB_SEN_MAM_3V3AUX_SCL

(kicad_pcb
	(version 20260206)
	(generator "pcbnew")
	(generator_version "10.0")
	(general
		(thickness 1.6)
		(legacy_teardrops no)
	)
	(paper "A4")
	(title_block
		(title "03242023_DA0F0TMBIJ0_F0T_Motherboard_J_brd_V01_OCP.brd")
		(comment 1 "Grand Teton / footprints 3522-3523 of 6105")
	)
	(layers
		(0 "F.Cu" signal "TOP")
		(4 "In1.Cu" signal "GND")
		(6 "In2.Cu" signal "IN1")
		(8 "In3.Cu" signal "GND1")
		(10 "In4.Cu" signal "IN2")
		(12 "In5.Cu" signal "GND2")
		(14 "In6.Cu" signal "IN3")
		(16 "In7.Cu" signal "GND3")
		(18 "In8.Cu" signal "VCC")
		(20 "In9.Cu" signal "VCC1")
		(22 "In10.Cu" signal "GND4")
		(24 "In11.Cu" signal "IN4")
		(26 "In12.Cu" signal "GND5")
		(28 "In13.Cu" signal "IN5")
		(30 "In14.Cu" signal "GND6")
		(32 "In15.Cu" signal "IN6")
		(34 "In16.Cu" signal "GND7")
		(2 "B.Cu" signal "BOTTOM")
		(9 "F.Adhes" user "F.Adhesive")
		(11 "B.Adhes" user "B.Adhesive")
		(13 "F.Paste" user "Package Geometry/Pastemask Top")
		(15 "B.Paste" user "Package Geometry/Pastemask Bottom")
		(5 "F.SilkS" user "Ref Des/Silkscreen Top")
		(7 "B.SilkS" user "Ref Des/Silkscreen Bottom")
		(1 "F.Mask" user "Board Geometry/Soldermask Top")
		(3 "B.Mask" user "Board Geometry/Soldermask Bottom")
		(17 "Dwgs.User" user "User.Drawings")
		(19 "Cmts.User" user "User.Comments")
		(21 "Eco1.User" user "User.Eco1")
		(23 "Eco2.User" user "User.Eco2")
		(25 "Edge.Cuts" user "Board Geometry/Outline")
		(27 "Margin" user)
		(31 "F.CrtYd" user "Package Geometry/Place Bound Top")
		(29 "B.CrtYd" user "Package Geometry/Place Bound Bottom")
		(35 "F.Fab" user "Ref Des/Assembly Top")
		(33 "B.Fab" user "Ref Des/Assembly Bottom")
	)
	(footprint ""
		(layer "F.Cu")
		(at 37.890196 -122.380502 -90)
		(property "Reference" "R1793"
			(at 0 0 270)
			(layer "F.SilkS")
			(hide yes)
			(effects
				(font
					(size 1.27 1.27)
				)
			)
		)
		(property "Value" ""
			(at 0 0 270)
			(layer "F.Fab")
			(effects
				(font
					(size 1.27 1.27)
				)
			)
		)
		(duplicate_pad_numbers_are_jumpers no)
		(fp_line
			(start -0.7874 0.4064)
			(end -0.7874 -0.4064)
			(stroke
				(width 0.1524)
				(type default)
			)
			(layer "F.SilkS")
		)
		(fp_line
			(start 0.7874 0.4064)
			(end -0.7874 0.4064)
			(stroke
				(width 0.1524)
				(type default)
			)
			(layer "F.SilkS")
		)
		(fp_line
			(start -0.7874 -0.4064)
			(end 0.7874 -0.4064)
			(stroke
				(width 0.1524)
				(type default)
			)
			(layer "F.SilkS")
		)
		(fp_line
			(start 0.7874 -0.4064)
			(end 0.7874 0.4064)
			(stroke
				(width 0.1524)
				(type default)
			)
			(layer "F.SilkS")
		)
		(fp_line
			(start -0.67945 0.3048)
			(end -0.67945 -0.305054)
			(stroke
				(width 0.1)
				(type default)
			)
			(layer "F.Fab")
		)
		(fp_line
			(start -0.12065 0.3048)
			(end -0.67945 0.3048)
			(stroke
				(width 0.1)
				(type default)
			)
			(layer "F.Fab")
		)
		(fp_line
			(start 0.120396 0.3048)
			(end 0.120396 0.2794)
			(stroke
				(width 0.1)
				(type default)
			)
			(layer "F.Fab")
		)
		(fp_line
			(start 0.67945 0.3048)
			(end 0.120396 0.3048)
			(stroke
				(width 0.1)
				(type default)
			)
			(layer "F.Fab")
		)
		(fp_line
			(start -0.12065 0.2794)
			(end -0.12065 0.3048)
			(stroke
				(width 0.1)
				(type default)
			)
			(layer "F.Fab")
		)
		(fp_line
			(start 0.120396 0.2794)
			(end -0.12065 0.2794)
			(stroke
				(width 0.1)
				(type default)
			)
			(layer "F.Fab")
		)
		(fp_line
			(start -0.12065 -0.2794)
			(end 0.12065 -0.2794)
			(stroke
				(width 0.1)
				(type default)
			)
			(layer "F.Fab")
		)
		(fp_line
			(start 0.12065 -0.2794)
			(end 0.12065 -0.3048)
			(stroke
				(width 0.1)
				(type default)
			)
			(layer "F.Fab")
		)
		(fp_line
			(start 0.12065 -0.3048)
			(end 0.67945 -0.3048)
			(stroke
				(width 0.1)
				(type default)
			)
			(layer "F.Fab")
		)
		(fp_line
			(start 0.67945 -0.3048)
			(end 0.67945 0.3048)
			(stroke
				(width 0.1)
				(type default)
			)
			(layer "F.Fab")
		)
		(fp_line
			(start -0.67945 -0.305054)
			(end -0.12065 -0.305054)
			(stroke
				(width 0.1)
				(type default)
			)
			(layer "F.Fab")
		)
		(fp_line
			(start -0.12065 -0.305054)
			(end -0.12065 -0.2794)
			(stroke
				(width 0.1)
				(type default)
			)
			(layer "F.Fab")
		)
		(pad "1" smd circle
			(at -0.40005 0 270)
			(size 0 0)
			(layers "F.Cu" "F.Mask" "F.Paste")
			(net "SMB_VR_3V3AUX_SCL_R1")
		)
		(pad "2" smd circle
			(at 0.40005 0 270)
			(size 0 0)
			(layers "F.Cu" "F.Mask" "F.Paste")
			(net "SMB_SEN_MAM_3V3AUX_SCL")
		)
	)
	(footprint ""
		(layer "F.Cu")
		(at 412.585662 -364.563914 90)
		(property "Reference" "PC600"
			(at 0 0 90)
			(layer "F.SilkS")
			(hide yes)
			(effects
				(font
					(size 1.27 1.27)
				)
			)
		)
		(property "Value" ""
			(at 0 0 90)
			(layer "F.Fab")
			(effects
				(font
					(size 1.27 1.27)
				)
			)
		)
		(duplicate_pad_numbers_are_jumpers no)
		(fp_line
			(start 0.7874 -0.4064)
			(end 0.7874 0.4064)
			(stroke
				(width 0.1524)
				(type default)
			)
			(layer "F.SilkS")
		)
		(fp_line
			(start -0.7874 -0.4064)
			(end 0.7874 -0.4064)
			(stroke
				(width 0.1524)
				(type default)
			)
			(layer "F.SilkS")
		)
		(fp_line
			(start 0.7874 0.4064)
			(end -0.7874 0.4064)
			(stroke
				(width 0.1524)
				(type default)
			)
			(layer "F.SilkS")
		)
		(fp_line
			(start -0.7874 0.4064)
			(end -0.7874 -0.4064)
			(stroke
				(width 0.1524)
				(type default)
			)
			(layer "F.SilkS")
		)
		(fp_line
			(start -0.12065 -0.305054)
			(end -0.12065 -0.2794)
			(stroke
				(width 0.1)
				(type default)
			)
			(layer "F.Fab")
		)
		(fp_line
			(start -0.67945 -0.305054)
			(end -0.12065 -0.305054)
			(stroke
				(width 0.1)
				(type default)
			)
			(layer "F.Fab")
		)
		(fp_line
			(start 0.67945 -0.3048)
			(end 0.67945 0.3048)
			(stroke
				(width 0.1)
				(type default)
			)
			(layer "F.Fab")
		)
		(fp_line
			(start 0.12065 -0.3048)
			(end 0.67945 -0.3048)
			(stroke
				(width 0.1)
				(type default)
			)
			(layer "F.Fab")
		)
		(fp_line
			(start 0.12065 -0.2794)
			(end 0.12065 -0.3048)
			(stroke
				(width 0.1)
				(type default)
			)
			(layer "F.Fab")
		)
		(fp_line
			(start -0.12065 -0.2794)
			(end 0.12065 -0.2794)
			(stroke
				(width 0.1)
				(type default)
			)
			(layer "F.Fab")
		)
		(fp_line
			(start 0.120396 0.2794)
			(end -0.12065 0.2794)
			(stroke
				(width 0.1)
				(type default)
			)
			(layer "F.Fab")
		)
		(fp_line
			(start -0.12065 0.2794)
			(end -0.12065 0.3048)
			(stroke
				(width 0.1)
				(type default)
			)
			(layer "F.Fab")
		)
		(fp_line
			(start 0.67945 0.3048)
			(end 0.120396 0.3048)
			(stroke
				(width 0.1)
				(type default)
			)
			(layer "F.Fab")
		)
		(fp_line
			(start 0.120396 0.3048)
			(end 0.120396 0.2794)
			(stroke
				(width 0.1)
				(type default)
			)
			(layer "F.Fab")
		)
		(fp_line
			(start -0.12065 0.3048)
			(end -0.67945 0.3048)
			(stroke
				(width 0.1)
				(type default)
			)
			(layer "F.Fab")
		)
		(fp_line
			(start -0.67945 0.3048)
			(end -0.67945 -0.305054)
			(stroke
				(width 0.1)
				(type default)
			)
			(layer "F.Fab")
		)
		(pad "1" smd circle
			(at -0.40005 0 90)
			(size 0 0)
			(layers "F.Cu" "F.Mask" "F.Paste")
			(net "PVCCFA_EHV_FIVRA_CPU0_VDD1")
		)
		(pad "2" smd circle
			(at 0.40005 0 90)
			(size 0 0)
			(layers "F.Cu" "F.Mask" "F.Paste")
			(net "GND")
		)
	)
)
